(kicad_pcb
	(version 20260206)
	(generator "pcbnew")
	(generator_version "10.0")
	(general
		(thickness 1.6)
		(legacy_teardrops no)
	)
	(paper "A4")
	(title_block
		(title "12092022_DA0F0TFB6D0_F0T_FAN_BOARD_MP5048_D_brd_v02_OCP.brd")
		(comment 1 "Grand Teton / footprints 833-837 of 924")
	)
	(layers
		(0 "F.Cu" signal "TOP")
		(4 "In1.Cu" signal "GND")
		(6 "In2.Cu" signal "IN1")
		(8 "In3.Cu" signal "IN2")
		(10 "In4.Cu" signal "GND1")
		(2 "B.Cu" signal "BOTTOM")
		(9 "F.Adhes" user "F.Adhesive")
		(11 "B.Adhes" user "B.Adhesive")
		(13 "F.Paste" user "Package Geometry/Pastemask Top")
		(15 "B.Paste" user "Package Geometry/Pastemask Bottom")
		(5 "F.SilkS" user "Ref Des/Silkscreen Top")
		(7 "B.SilkS" user "Ref Des/Silkscreen Bottom")
		(1 "F.Mask" user "Board Geometry/Soldermask Top")
		(3 "B.Mask" user "Board Geometry/Soldermask Bottom")
		(17 "Dwgs.User" user "User.Drawings")
		(19 "Cmts.User" user "User.Comments")
		(21 "Eco1.User" user "User.Eco1")
		(23 "Eco2.User" user "User.Eco2")
		(25 "Edge.Cuts" user "Board Geometry/Outline")
		(27 "Margin" user)
		(31 "F.CrtYd" user "Package Geometry/Place Bound Top")
		(29 "B.CrtYd" user "Package Geometry/Place Bound Bottom")
		(35 "F.Fab" user "Ref Des/Assembly Top")
		(33 "B.Fab" user "Ref Des/Assembly Bottom")
	)
	(footprint ""
		(layer "B.Cu")
		(at 6.914642 -225.445828 180)
		(property "Reference" "PD12"
			(at 1.961642 -3.857498 0)
			(unlocked yes)
			(layer "B.SilkS")
			(effects
				(font
					(size 0.7874 0.5842)
					(thickness 0.1524)
				)
				(justify left mirror)
			)
		)
		(property "Value" ""
			(at 0 0 0)
			(layer "B.Fab")
			(effects
				(font
					(size 1.27 1.27)
				)
				(justify mirror)
			)
		)
		(duplicate_pad_numbers_are_jumpers no)
		(fp_line
			(start 4.826 3.109976)
			(end 4.826 0)
			(stroke
				(width 0.1524)
				(type default)
			)
			(layer "B.SilkS")
		)
		(fp_line
			(start 4.826 0)
			(end 4.826 -3.109976)
			(stroke
				(width 0.1524)
				(type default)
			)
			(layer "B.SilkS")
		)
		(fp_line
			(start 4.826 -3.109976)
			(end -4.826 -3.109976)
			(stroke
				(width 0.1524)
				(type default)
			)
			(layer "B.SilkS")
		)
		(fp_line
			(start 1.0922 0)
			(end 1.7018 0)
			(stroke
				(width 0.1524)
				(type default)
			)
			(layer "B.SilkS")
		)
		(fp_line
			(start 1.016 1.016)
			(end -1.016 0)
			(stroke
				(width 0.1524)
				(type default)
			)
			(layer "B.SilkS")
		)
		(fp_line
			(start 1.016 -1.016)
			(end 1.016 1.016)
			(stroke
				(width 0.1524)
				(type default)
			)
			(layer "B.SilkS")
		)
		(fp_line
			(start -1.143 1.397)
			(end -1.143 -1.397)
			(stroke
				(width 0.1524)
				(type default)
			)
			(layer "B.SilkS")
		)
		(fp_line
			(start -1.143 0)
			(end 1.016 -1.016)
			(stroke
				(width 0.1524)
				(type default)
			)
			(layer "B.SilkS")
		)
		(fp_line
			(start -1.143 0)
			(end -1.8034 0)
			(stroke
				(width 0.1524)
				(type default)
			)
			(layer "B.SilkS")
		)
		(fp_line
			(start -4.8133 -3.109976)
			(end -5.3467 -3.109976)
			(stroke
				(width 0.1524)
				(type default)
			)
			(layer "B.SilkS")
		)
		(fp_line
			(start -4.826 3.109976)
			(end 4.826 3.109976)
			(stroke
				(width 0.1524)
				(type default)
			)
			(layer "B.SilkS")
		)
		(fp_line
			(start -4.826 0)
			(end -4.826 3.109976)
			(stroke
				(width 0.1524)
				(type default)
			)
			(layer "B.SilkS")
		)
		(fp_line
			(start -4.826 -3.109976)
			(end -4.826 0)
			(stroke
				(width 0.1524)
				(type default)
			)
			(layer "B.SilkS")
		)
		(fp_line
			(start -4.9276 3.109976)
			(end -4.9276 -3.109976)
			(stroke
				(width 0.1524)
				(type default)
			)
			(layer "B.SilkS")
		)
		(fp_line
			(start -5.0292 3.109976)
			(end -5.0292 -3.109976)
			(stroke
				(width 0.1524)
				(type default)
			)
			(layer "B.SilkS")
		)
		(fp_line
			(start -5.1308 3.109976)
			(end -5.1308 -3.109976)
			(stroke
				(width 0.1524)
				(type default)
			)
			(layer "B.SilkS")
		)
		(fp_line
			(start -5.207 3.109976)
			(end -5.207 -3.109976)
			(stroke
				(width 0.1524)
				(type default)
			)
			(layer "B.SilkS")
		)
		(fp_line
			(start -5.334 3.109976)
			(end -4.8133 3.109976)
			(stroke
				(width 0.1524)
				(type default)
			)
			(layer "B.SilkS")
		)
		(fp_line
			(start -5.334 3.109976)
			(end -5.334 0)
			(stroke
				(width 0.1524)
				(type default)
			)
			(layer "B.SilkS")
		)
		(fp_line
			(start -5.334 0)
			(end -5.334 -3.109976)
			(stroke
				(width 0.1524)
				(type default)
			)
			(layer "B.SilkS")
		)
		(fp_line
			(start 3.554984 3.109976)
			(end 3.554984 -3.109976)
			(stroke
				(width 0.1)
				(type default)
			)
			(layer "B.Fab")
		)
		(fp_line
			(start 3.554984 -3.109976)
			(end -3.554984 -3.109976)
			(stroke
				(width 0.1)
				(type default)
			)
			(layer "B.Fab")
		)
		(fp_line
			(start 1.0922 0)
			(end 1.7018 0)
			(stroke
				(width 0.1)
				(type default)
			)
			(layer "B.Fab")
		)
		(fp_line
			(start 1.016 1.016)
			(end -1.016 0)
			(stroke
				(width 0.1)
				(type default)
			)
			(layer "B.Fab")
		)
		(fp_line
			(start 1.016 -1.016)
			(end 1.016 1.016)
			(stroke
				(width 0.1)
				(type default)
			)
			(layer "B.Fab")
		)
		(fp_line
			(start -1.143 1.397)
			(end -1.143 -1.397)
			(stroke
				(width 0.1)
				(type default)
			)
			(layer "B.Fab")
		)
		(fp_line
			(start -1.143 0)
			(end 1.016 -1.016)
			(stroke
				(width 0.1)
				(type default)
			)
			(layer "B.Fab")
		)
		(fp_line
			(start -1.143 0)
			(end -1.8034 0)
			(stroke
				(width 0.1)
				(type default)
			)
			(layer "B.Fab")
		)
		(fp_line
			(start -3.554984 3.109976)
			(end 3.554984 3.109976)
			(stroke
				(width 0.1)
				(type default)
			)
			(layer "B.Fab")
		)
		(fp_line
			(start -3.554984 -3.109976)
			(end -3.554984 3.109976)
			(stroke
				(width 0.1)
				(type default)
			)
			(layer "B.Fab")
		)
		(fp_text user "+"
			(at 4.5466 0.19685 0)
			(unlocked yes)
			(layer "B.SilkS")
			(effects
				(font
					(size 1.905 1.4224)
					(thickness 0.1524)
				)
				(justify left mirror)
			)
		)
		(fp_text user "-"
			(at -6.6802 0.22225 0)
			(unlocked yes)
			(layer "B.SilkS")
			(effects
				(font
					(size 1.905 1.4224)
					(thickness 0.1524)
				)
				(justify left mirror)
			)
		)
		(fp_text user "+"
			(at 4.5466 0.19685 0)
			(unlocked yes)
			(layer "B.Fab")
			(effects
				(font
					(size 1.905 1.4224)
					(thickness 0.1524)
				)
				(justify left mirror)
			)
		)
		(fp_text user "-"
			(at -6.6802 0.22225 0)
			(unlocked yes)
			(layer "B.Fab")
			(effects
				(font
					(size 1.905 1.4224)
					(thickness 0.1524)
				)
				(justify left mirror)
			)
		)
		(pad "A" smd rect
			(at 3.400044 0 180)
			(size 2.5146 3.302)
			(layers "B.Cu" "B.Mask" "B.Paste")
			(net "GND")
		)
		(pad "C" smd rect
			(at -3.400044 0 180)
			(size 2.5146 3.302)
			(layers "B.Cu" "B.Mask" "B.Paste")
			(net "P52V_FAN_6")
		)
	)
	(footprint ""
		(layer "B.Cu")
		(at 10.445242 -73.962768 90)
		(property "Reference" "PR60"
			(at 0 0 90)
			(layer "B.SilkS")
			(hide yes)
			(effects
				(font
					(size 1.27 1.27)
				)
				(justify mirror)
			)
		)
		(property "Value" ""
			(at 0 0 90)
			(layer "B.Fab")
			(effects
				(font
					(size 1.27 1.27)
				)
				(justify mirror)
			)
		)
		(duplicate_pad_numbers_are_jumpers no)
		(fp_line
			(start 0.7874 -0.4064)
			(end -0.7874 -0.4064)
			(stroke
				(width 0.1524)
				(type default)
			)
			(layer "B.SilkS")
		)
		(fp_line
			(start -0.7874 -0.4064)
			(end -0.7874 0.4064)
			(stroke
				(width 0.1524)
				(type default)
			)
			(layer "B.SilkS")
		)
		(fp_line
			(start 0.7874 0.4064)
			(end 0.7874 -0.4064)
			(stroke
				(width 0.1524)
				(type default)
			)
			(layer "B.SilkS")
		)
		(fp_line
			(start -0.7874 0.4064)
			(end 0.7874 0.4064)
			(stroke
				(width 0.1524)
				(type default)
			)
			(layer "B.SilkS")
		)
		(fp_line
			(start 0.67945 -0.305054)
			(end 0.12065 -0.305054)
			(stroke
				(width 0.1)
				(type default)
			)
			(layer "B.Fab")
		)
		(fp_line
			(start 0.12065 -0.305054)
			(end 0.12065 -0.2794)
			(stroke
				(width 0.1)
				(type default)
			)
			(layer "B.Fab")
		)
		(fp_line
			(start -0.12065 -0.3048)
			(end -0.67945 -0.3048)
			(stroke
				(width 0.1)
				(type default)
			)
			(layer "B.Fab")
		)
		(fp_line
			(start -0.67945 -0.3048)
			(end -0.67945 0.3048)
			(stroke
				(width 0.1)
				(type default)
			)
			(layer "B.Fab")
		)
		(fp_line
			(start 0.12065 -0.2794)
			(end -0.12065 -0.2794)
			(stroke
				(width 0.1)
				(type default)
			)
			(layer "B.Fab")
		)
		(fp_line
			(start -0.12065 -0.2794)
			(end -0.12065 -0.3048)
			(stroke
				(width 0.1)
				(type default)
			)
			(layer "B.Fab")
		)
		(fp_line
			(start 0.12065 0.2794)
			(end 0.12065 0.3048)
			(stroke
				(width 0.1)
				(type default)
			)
			(layer "B.Fab")
		)
		(fp_line
			(start -0.120396 0.2794)
			(end 0.12065 0.2794)
			(stroke
				(width 0.1)
				(type default)
			)
			(layer "B.Fab")
		)
		(fp_line
			(start 0.67945 0.3048)
			(end 0.67945 -0.305054)
			(stroke
				(width 0.1)
				(type default)
			)
			(layer "B.Fab")
		)
		(fp_line
			(start 0.12065 0.3048)
			(end 0.67945 0.3048)
			(stroke
				(width 0.1)
				(type default)
			)
			(layer "B.Fab")
		)
		(fp_line
			(start -0.120396 0.3048)
			(end -0.120396 0.2794)
			(stroke
				(width 0.1)
				(type default)
			)
			(layer "B.Fab")
		)
		(fp_line
			(start -0.67945 0.3048)
			(end -0.120396 0.3048)
			(stroke
				(width 0.1)
				(type default)
			)
			(layer "B.Fab")
		)
		(pad "1" smd circle
			(at 0.40005 0 270)
			(size 0 0)
			(layers "B.Cu" "B.Mask" "B.Paste")
			(net "FAN_5_TEMP")
		)
		(pad "2" smd circle
			(at -0.40005 0 270)
			(size 0 0)
			(layers "B.Cu" "B.Mask" "B.Paste")
			(net "GND")
		)
	)
	(footprint ""
		(layer "B.Cu")
		(at 44.667932 -71.177912 -90)
		(property "Reference" "U396"
			(at 1.378712 -2.981198 270)
			(unlocked yes)
			(layer "B.SilkS")
			(effects
				(font
					(size 0.7874 0.5842)
					(thickness 0.1524)
				)
				(justify left mirror)
			)
		)
		(property "Value" ""
			(at 0 0 90)
			(layer "B.Fab")
			(effects
				(font
					(size 1.27 1.27)
				)
				(justify mirror)
			)
		)
		(duplicate_pad_numbers_are_jumpers no)
		(fp_line
			(start -1.3462 1.1938)
			(end -1.3462 -1.1938)
			(stroke
				(width 0.1524)
				(type default)
			)
			(layer "B.SilkS")
		)
		(fp_line
			(start 1.3462 1.1938)
			(end -1.3462 1.1938)
			(stroke
				(width 0.1524)
				(type default)
			)
			(layer "B.SilkS")
		)
		(fp_line
			(start -1.3462 -1.1938)
			(end 1.3462 -1.1938)
			(stroke
				(width 0.1524)
				(type default)
			)
			(layer "B.SilkS")
		)
		(fp_line
			(start 1.3462 -1.1938)
			(end 1.3462 1.1684)
			(stroke
				(width 0.1524)
				(type default)
			)
			(layer "B.SilkS")
		)
		(fp_poly
			(pts
				(xy 1.447038 -0.760476) (xy 2.052066 -0.457962) (xy 2.052066 -1.06299)
			)
			(stroke
				(width 0)
				(type default)
			)
			(fill yes)
			(layer "B.SilkS")
		)
		(fp_line
			(start -0.674878 1.124966)
			(end -0.674878 -1.124966)
			(stroke
				(width 0.1)
				(type default)
			)
			(layer "B.Fab")
		)
		(fp_line
			(start 0.674878 1.124966)
			(end -0.674878 1.124966)
			(stroke
				(width 0.1)
				(type default)
			)
			(layer "B.Fab")
		)
		(fp_line
			(start -0.674878 -1.124966)
			(end 0.674878 -1.124966)
			(stroke
				(width 0.1)
				(type default)
			)
			(layer "B.Fab")
		)
		(fp_line
			(start 0.674878 -1.124966)
			(end 0.674878 1.124966)
			(stroke
				(width 0.1)
				(type default)
			)
			(layer "B.Fab")
		)
		(fp_poly
			(pts
				(xy 1.447038 -0.760476) (xy 2.052066 -0.457962) (xy 2.052066 -1.06299)
			)
			(stroke
				(width 0)
				(type default)
			)
			(fill yes)
			(layer "B.Fab")
		)
		(pad "1" smd rect
			(at 0.899922 -0.750062 90)
			(size 0.6096 0.6096)
			(layers "B.Cu" "B.Mask" "B.Paste")
			(net "NC_U396_P1")
		)
		(pad "2" smd rect
			(at 0.899922 0)
			(size 0.4064 0.6096)
			(layers "B.Cu" "B.Mask" "B.Paste")
			(net "FAN_2_PRSNT_BUF_N")
		)
		(pad "3" smd rect
			(at 0.899922 0.750062 90)
			(size 0.6096 0.6096)
			(layers "B.Cu" "B.Mask" "B.Paste")
			(net "GND")
		)
		(pad "4" smd rect
			(at -0.899922 0.750062 90)
			(size 0.6096 0.6096)
			(layers "B.Cu" "B.Mask" "B.Paste")
			(net "FAN_2_PRESENT")
		)
		(pad "5" smd rect
			(at -0.899922 -0.750062 90)
			(size 0.6096 0.6096)
			(layers "B.Cu" "B.Mask" "B.Paste")
			(net "P3V3_AUX")
		)
	)
	(footprint ""
		(layer "B.Cu")
		(at 40.894 -131.191 180)
		(property "Reference" "R5429"
			(at 0 0 0)
			(layer "B.SilkS")
			(hide yes)
			(effects
				(font
					(size 1.27 1.27)
				)
				(justify mirror)
			)
		)
		(property "Value" ""
			(at 0 0 0)
			(layer "B.Fab")
			(effects
				(font
					(size 1.27 1.27)
				)
				(justify mirror)
			)
		)
		(duplicate_pad_numbers_are_jumpers no)
		(fp_line
			(start 0.7874 0.4064)
			(end 0.7874 -0.4064)
			(stroke
				(width 0.1524)
				(type default)
			)
			(layer "B.SilkS")
		)
		(fp_line
			(start 0.7874 -0.4064)
			(end -0.7874 -0.4064)
			(stroke
				(width 0.1524)
				(type default)
			)
			(layer "B.SilkS")
		)
		(fp_line
			(start -0.7874 0.4064)
			(end 0.7874 0.4064)
			(stroke
				(width 0.1524)
				(type default)
			)
			(layer "B.SilkS")
		)
		(fp_line
			(start -0.7874 -0.4064)
			(end -0.7874 0.4064)
			(stroke
				(width 0.1524)
				(type default)
			)
			(layer "B.SilkS")
		)
		(fp_line
			(start 0.67945 0.3048)
			(end 0.67945 -0.305054)
			(stroke
				(width 0.1)
				(type default)
			)
			(layer "B.Fab")
		)
		(fp_line
			(start 0.67945 -0.305054)
			(end 0.12065 -0.305054)
			(stroke
				(width 0.1)
				(type default)
			)
			(layer "B.Fab")
		)
		(fp_line
			(start 0.12065 0.3048)
			(end 0.67945 0.3048)
			(stroke
				(width 0.1)
				(type default)
			)
			(layer "B.Fab")
		)
		(fp_line
			(start 0.12065 0.2794)
			(end 0.12065 0.3048)
			(stroke
				(width 0.1)
				(type default)
			)
			(layer "B.Fab")
		)
		(fp_line
			(start 0.12065 -0.2794)
			(end -0.12065 -0.2794)
			(stroke
				(width 0.1)
				(type default)
			)
			(layer "B.Fab")
		)
		(fp_line
			(start 0.12065 -0.305054)
			(end 0.12065 -0.2794)
			(stroke
				(width 0.1)
				(type default)
			)
			(layer "B.Fab")
		)
		(fp_line
			(start -0.120396 0.3048)
			(end -0.120396 0.2794)
			(stroke
				(width 0.1)
				(type default)
			)
			(layer "B.Fab")
		)
		(fp_line
			(start -0.120396 0.2794)
			(end 0.12065 0.2794)
			(stroke
				(width 0.1)
				(type default)
			)
			(layer "B.Fab")
		)
		(fp_line
			(start -0.12065 -0.2794)
			(end -0.12065 -0.3048)
			(stroke
				(width 0.1)
				(type default)
			)
			(layer "B.Fab")
		)
		(fp_line
			(start -0.12065 -0.3048)
			(end -0.67945 -0.3048)
			(stroke
				(width 0.1)
				(type default)
			)
			(layer "B.Fab")
		)
		(fp_line
			(start -0.67945 0.3048)
			(end -0.120396 0.3048)
			(stroke
				(width 0.1)
				(type default)
			)
			(layer "B.Fab")
		)
		(fp_line
			(start -0.67945 -0.3048)
			(end -0.67945 0.3048)
			(stroke
				(width 0.1)
				(type default)
			)
			(layer "B.Fab")
		)
		(pad "1" smd rect
			(at 0.40005 0 180)
			(size 0.4572 0.508)
			(layers "B.Cu" "B.Mask" "B.Paste")
			(net "FAN_1_TACH_OL")
		)
		(pad "2" smd rect
			(at -0.40005 0 180)
			(size 0.4572 0.508)
			(layers "B.Cu" "B.Mask" "B.Paste")
			(net "GND")
		)
	)
	(footprint ""
		(layer "B.Cu")
		(at 11.461242 -73.962768 90)
		(property "Reference" "PC45"
			(at 0 0 90)
			(layer "B.SilkS")
			(hide yes)
			(effects
				(font
					(size 1.27 1.27)
				)
				(justify mirror)
			)
		)
		(property "Value" ""
			(at 0 0 90)
			(layer "B.Fab")
			(effects
				(font
					(size 1.27 1.27)
				)
				(justify mirror)
			)
		)
		(duplicate_pad_numbers_are_jumpers no)
		(fp_line
			(start 0.7874 -0.4064)
			(end -0.7874 -0.4064)
			(stroke
				(width 0.1524)
				(type default)
			)
			(layer "B.SilkS")
		)
		(fp_line
			(start -0.7874 -0.4064)
			(end -0.7874 0.4064)
			(stroke
				(width 0.1524)
				(type default)
			)
			(layer "B.SilkS")
		)
		(fp_line
			(start 0.7874 0.4064)
			(end 0.7874 -0.4064)
			(stroke
				(width 0.1524)
				(type default)
			)
			(layer "B.SilkS")
		)
		(fp_line
			(start -0.7874 0.4064)
			(end 0.7874 0.4064)
			(stroke
				(width 0.1524)
				(type default)
			)
			(layer "B.SilkS")
		)
		(fp_line
			(start 0.67945 -0.305054)
			(end 0.12065 -0.305054)
			(stroke
				(width 0.1)
				(type default)
			)
			(layer "B.Fab")
		)
		(fp_line
			(start 0.12065 -0.305054)
			(end 0.12065 -0.2794)
			(stroke
				(width 0.1)
				(type default)
			)
			(layer "B.Fab")
		)
		(fp_line
			(start -0.12065 -0.3048)
			(end -0.67945 -0.3048)
			(stroke
				(width 0.1)
				(type default)
			)
			(layer "B.Fab")
		)
		(fp_line
			(start -0.67945 -0.3048)
			(end -0.67945 0.3048)
			(stroke
				(width 0.1)
				(type default)
			)
			(layer "B.Fab")
		)
		(fp_line
			(start 0.12065 -0.2794)
			(end -0.12065 -0.2794)
			(stroke
				(width 0.1)
				(type default)
			)
			(layer "B.Fab")
		)
		(fp_line
			(start -0.12065 -0.2794)
			(end -0.12065 -0.3048)
			(stroke
				(width 0.1)
				(type default)
			)
			(layer "B.Fab")
		)
		(fp_line
			(start 0.12065 0.2794)
			(end 0.12065 0.3048)
			(stroke
				(width 0.1)
				(type default)
			)
			(layer "B.Fab")
		)
		(fp_line
			(start -0.120396 0.2794)
			(end 0.12065 0.2794)
			(stroke
				(width 0.1)
				(type default)
			)
			(layer "B.Fab")
		)
		(fp_line
			(start 0.67945 0.3048)
			(end 0.67945 -0.305054)
			(stroke
				(width 0.1)
				(type default)
			)
			(layer "B.Fab")
		)
		(fp_line
			(start 0.12065 0.3048)
			(end 0.67945 0.3048)
			(stroke
				(width 0.1)
				(type default)
			)
			(layer "B.Fab")
		)
		(fp_line
			(start -0.120396 0.3048)
			(end -0.120396 0.2794)
			(stroke
				(width 0.1)
				(type default)
			)
			(layer "B.Fab")
		)
		(fp_line
			(start -0.67945 0.3048)
			(end -0.120396 0.3048)
			(stroke
				(width 0.1)
				(type default)
			)
			(layer "B.Fab")
		)
		(pad "1" smd circle
			(at 0.40005 0 270)
			(size 0 0)
			(layers "B.Cu" "B.Mask" "B.Paste")
			(net "FAN_5_P5V")
		)
		(pad "2" smd circle
			(at -0.40005 0 270)
			(size 0 0)
			(layers "B.Cu" "B.Mask" "B.Paste")
			(net "GND")
		)
	)
)
